# S9S_MB_2U (Grand Teton) — schematic netlist excerpt (pin names and nets, part order shuffled) for the footprints in the layout excerpt that follows; sources: Cadence DE-HDL packaged netlist, KiCad conversion of 03242023_DA0F0TMBIJ0_F0T_Motherboard_J_brd_V01_OCP.brd

C259  Q_CAP  10UF 6.3V 20% X6S  pkg C0402  page 77 : A = PVCCIN_CPU1 ; B = GND

(kicad_pcb
	(version 20260206)
	(generator "pcbnew")
	(generator_version "10.0")
	(general
		(thickness 1.6)
		(legacy_teardrops no)
	)
	(paper "A4")
	(title_block
		(title "03242023_DA0F0TMBIJ0_F0T_Motherboard_J_brd_V01_OCP.brd")
		(comment 1 "Grand Teton / footprints 3244-3244 of 6105")
	)
	(layers
		(0 "F.Cu" signal "TOP")
		(4 "In1.Cu" signal "GND")
		(6 "In2.Cu" signal "IN1")
		(8 "In3.Cu" signal "GND1")
		(10 "In4.Cu" signal "IN2")
		(12 "In5.Cu" signal "GND2")
		(14 "In6.Cu" signal "IN3")
		(16 "In7.Cu" signal "GND3")
		(18 "In8.Cu" signal "VCC")
		(20 "In9.Cu" signal "VCC1")
		(22 "In10.Cu" signal "GND4")
		(24 "In11.Cu" signal "IN4")
		(26 "In12.Cu" signal "GND5")
		(28 "In13.Cu" signal "IN5")
		(30 "In14.Cu" signal "GND6")
		(32 "In15.Cu" signal "IN6")
		(34 "In16.Cu" signal "GND7")
		(2 "B.Cu" signal "BOTTOM")
		(9 "F.Adhes" user "F.Adhesive")
		(11 "B.Adhes" user "B.Adhesive")
		(13 "F.Paste" user "Package Geometry/Pastemask Top")
		(15 "B.Paste" user "Package Geometry/Pastemask Bottom")
		(5 "F.SilkS" user "Ref Des/Silkscreen Top")
		(7 "B.SilkS" user "Ref Des/Silkscreen Bottom")
		(1 "F.Mask" user "Board Geometry/Soldermask Top")
		(3 "B.Mask" user "Board Geometry/Soldermask Bottom")
		(17 "Dwgs.User" user "User.Drawings")
		(19 "Cmts.User" user "User.Comments")
		(21 "Eco1.User" user "User.Eco1")
		(23 "Eco2.User" user "User.Eco2")
		(25 "Edge.Cuts" user "Board Geometry/Outline")
		(27 "Margin" user)
		(31 "F.CrtYd" user "Package Geometry/Place Bound Top")
		(29 "B.CrtYd" user "Package Geometry/Place Bound Bottom")
		(35 "F.Fab" user "Ref Des/Assembly Top")
		(33 "B.Fab" user "Ref Des/Assembly Bottom")
	)
	(footprint ""
		(layer "F.Cu")
		(at 117.526816 -245.634256 -90)
		(property "Reference" "C259"
			(at 0 0 270)
			(layer "F.SilkS")
			(hide yes)
			(effects
				(font
					(size 1.27 1.27)
				)
			)
		)
		(property "Value" ""
			(at 0 0 270)
			(layer "F.Fab")
			(effects
				(font
					(size 1.27 1.27)
				)
			)
		)
		(duplicate_pad_numbers_are_jumpers no)
		(fp_line
			(start -0.7874 0.4064)
			(end -0.7874 -0.4064)
			(stroke
				(width 0.1524)
				(type default)
			)
			(layer "F.SilkS")
		)
		(fp_line
			(start 0.7874 0.4064)
			(end -0.7874 0.4064)
			(stroke
				(width 0.1524)
				(type default)
			)
			(layer "F.SilkS")
		)
		(fp_line
			(start -0.7874 -0.4064)
			(end 0.7874 -0.4064)
			(stroke
				(width 0.1524)
				(type default)
			)
			(layer "F.SilkS")
		)
		(fp_line
			(start 0.7874 -0.4064)
			(end 0.7874 0.4064)
			(stroke
				(width 0.1524)
				(type default)
			)
			(layer "F.SilkS")
		)
		(fp_line
			(start -0.67945 0.3048)
			(end -0.67945 -0.305054)
			(stroke
				(width 0.1)
				(type default)
			)
			(layer "F.Fab")
		)
		(fp_line
			(start -0.12065 0.3048)
			(end -0.67945 0.3048)
			(stroke
				(width 0.1)
				(type default)
			)
			(layer "F.Fab")
		)
		(fp_line
			(start 0.120396 0.3048)
			(end 0.120396 0.2794)
			(stroke
				(width 0.1)
				(type default)
			)
			(layer "F.Fab")
		)
		(fp_line
			(start 0.67945 0.3048)
			(end 0.120396 0.3048)
			(stroke
				(width 0.1)
				(type default)
			)
			(layer "F.Fab")
		)
		(fp_line
			(start -0.12065 0.2794)
			(end -0.12065 0.3048)
			(stroke
				(width 0.1)
				(type default)
			)
			(layer "F.Fab")
		)
		(fp_line
			(start 0.120396 0.2794)
			(end -0.12065 0.2794)
			(stroke
				(width 0.1)
				(type default)
			)
			(layer "F.Fab")
		)
		(fp_line
			(start -0.12065 -0.2794)
			(end 0.12065 -0.2794)
			(stroke
				(width 0.1)
				(type default)
			)
			(layer "F.Fab")
		)
		(fp_line
			(start 0.12065 -0.2794)
			(end 0.12065 -0.3048)
			(stroke
				(width 0.1)
				(type default)
			)
			(layer "F.Fab")
		)
		(fp_line
			(start 0.12065 -0.3048)
			(end 0.67945 -0.3048)
			(stroke
				(width 0.1)
				(type default)
			)
			(layer "F.Fab")
		)
		(fp_line
			(start 0.67945 -0.3048)
			(end 0.67945 0.3048)
			(stroke
				(width 0.1)
				(type default)
			)
			(layer "F.Fab")
		)
		(fp_line
			(start -0.67945 -0.305054)
			(end -0.12065 -0.305054)
			(stroke
				(width 0.1)
				(type default)
			)
			(layer "F.Fab")
		)
		(fp_line
			(start -0.12065 -0.305054)
			(end -0.12065 -0.2794)
			(stroke
				(width 0.1)
				(type default)
			)
			(layer "F.Fab")
		)
		(pad "1" smd circle
			(at -0.40005 0 270)
			(size 0 0)
			(layers "F.Cu" "F.Mask" "F.Paste")
			(net "PVCCIN_CPU1")
		)
		(pad "2" smd circle
			(at 0.40005 0 270)
			(size 0 0)
			(layers "F.Cu" "F.Mask" "F.Paste")
			(net "GND")
		)
	)
)
